G04*
G04 #@! TF.GenerationSoftware,Altium Limited,Altium Designer,23.6.0 (18)*
G04*
G04 Layer_Physical_Order=4*
G04 Layer_Color=16711680*
%FSLAX44Y44*%
%MOMM*%
G71*
G04*
G04 #@! TF.SameCoordinates,B62FFF2A-40BB-47C2-B022-6C0D6E2DF31E*
G04*
G04*
G04 #@! TF.FilePolarity,Positive*
G04*
G01*
G75*
%ADD17C,0.2540*%
%ADD61C,0.1905*%
%ADD62C,0.2413*%
%ADD65C,0.4064*%
%ADD67R,0.3500X1.9500*%
%ADD68C,0.2032*%
%ADD69C,6.0000*%
G36*
X215922Y54045D02*
X214652Y53204D01*
X199489D01*
X198517Y52801D01*
X198114Y51829D01*
Y50789D01*
X197821Y50081D01*
X197315Y49575D01*
X197226Y49360D01*
X197051Y49205D01*
X196840Y48772D01*
X196818Y48399D01*
X196708Y48042D01*
X196812Y46922D01*
X197030Y46509D01*
X197209Y46078D01*
X197507Y45780D01*
X197801Y45071D01*
Y44304D01*
X197507Y43596D01*
X196965Y43054D01*
X196257Y42761D01*
X195865D01*
X195411Y42572D01*
X194946Y42409D01*
X193872Y41443D01*
X193745Y41178D01*
X193681Y41117D01*
X193641Y41096D01*
X193633Y41072D01*
X193533Y40976D01*
X193446Y40779D01*
X193440Y40542D01*
X193417Y40494D01*
X193438Y40436D01*
X193438Y40426D01*
X193335Y40089D01*
X193372Y39719D01*
X193470Y39535D01*
Y39327D01*
X193709Y39089D01*
X193868Y38791D01*
X193964Y38761D01*
X194634Y38092D01*
X194927Y37383D01*
Y36617D01*
X194634Y35908D01*
X194092Y35366D01*
X193131Y34968D01*
X192937Y34775D01*
X192685Y34670D01*
X192580Y34417D01*
X192555Y34393D01*
X174673D01*
X174123Y35217D01*
X172467Y36872D01*
X171144Y37757D01*
X171144Y37757D01*
X168981Y38652D01*
X168981Y38653D01*
X167421Y38963D01*
X165079D01*
X163519Y38653D01*
X163519Y38652D01*
X161356Y37757D01*
X160033Y36872D01*
X158377Y35217D01*
X157826Y34393D01*
X107326D01*
Y42121D01*
X113650Y48445D01*
X114727Y47726D01*
X114698Y47657D01*
Y46343D01*
X115201Y45130D01*
X116130Y44201D01*
X117343Y43698D01*
X118657D01*
X119870Y44201D01*
X120612Y44942D01*
X121749Y45054D01*
X125353Y46148D01*
X128675Y47923D01*
X131587Y50313D01*
X131588Y50312D01*
X134020Y53276D01*
X135828Y56657D01*
X136941Y60326D01*
X137317Y64142D01*
X137266D01*
Y129479D01*
X137308D01*
X136967Y133813D01*
X135952Y138041D01*
X134288Y142058D01*
X132016Y145765D01*
X129192Y149071D01*
X129215Y149094D01*
X126384Y151266D01*
X123088Y152631D01*
X119551Y153097D01*
Y153023D01*
X99278D01*
Y153065D01*
X94944Y152724D01*
X90716Y151709D01*
X86699Y150045D01*
X83205Y147904D01*
X83205Y147904D01*
X82932Y147642D01*
X82349Y147060D01*
X82347Y147057D01*
X82316Y147027D01*
X79605Y144316D01*
X79575Y144270D01*
X76484Y141734D01*
X72910Y139824D01*
X69033Y138647D01*
X66250Y138373D01*
X65000Y138325D01*
Y138325D01*
X61899Y137917D01*
X59009Y136720D01*
X57510Y135569D01*
X56530Y134818D01*
X56528Y134816D01*
X56569Y134774D01*
X39105Y117309D01*
X39071Y117343D01*
X38930Y117131D01*
X38130Y116799D01*
X37201Y115870D01*
X36698Y114657D01*
Y113343D01*
X37201Y112130D01*
X38130Y111201D01*
X39343Y110698D01*
X40657D01*
X41870Y111201D01*
X42799Y112130D01*
X43302Y113343D01*
Y114657D01*
X43173Y114968D01*
X59774Y131569D01*
X59788Y131555D01*
X59790Y131556D01*
X61315Y132726D01*
X63092Y133462D01*
X64943Y133706D01*
X65000Y133656D01*
Y133656D01*
X69929Y134141D01*
X74669Y135579D01*
X79037Y137914D01*
X79458Y138259D01*
X82865Y141056D01*
X82810Y141111D01*
X85878Y144179D01*
X86410Y144616D01*
X90414Y146756D01*
X94760Y148074D01*
X99184Y148510D01*
X99278Y148491D01*
X119551D01*
Y148485D01*
X121895Y148177D01*
X124079Y147272D01*
X125954Y145833D01*
X126764Y144899D01*
X128858Y142347D01*
X130999Y138343D01*
X132317Y133998D01*
X132753Y129573D01*
X132734Y129479D01*
Y64142D01*
X132723D01*
X132435Y61223D01*
X131583Y58415D01*
X130201Y55828D01*
X128339Y53560D01*
X127397Y52770D01*
X125338Y51190D01*
X121798Y49724D01*
X120161Y49509D01*
X119870Y49799D01*
X118657Y50302D01*
X117343D01*
X117274Y50273D01*
X116555Y51350D01*
X126602Y61398D01*
X127093Y62133D01*
X127266Y63000D01*
Y134346D01*
X127799Y134880D01*
X128302Y136093D01*
Y137407D01*
X127799Y138620D01*
X126870Y139549D01*
X125657Y140052D01*
X124343D01*
X123130Y139549D01*
X122201Y138620D01*
X121698Y137407D01*
Y136093D01*
X122201Y134880D01*
X122734Y134346D01*
Y63939D01*
X103596Y44801D01*
X103025Y44889D01*
X102326Y45255D01*
Y63940D01*
X102154Y64807D01*
X101662Y65542D01*
X96266Y70939D01*
Y134346D01*
X96799Y134880D01*
X97302Y136093D01*
Y137407D01*
X96799Y138620D01*
X95870Y139549D01*
X94657Y140052D01*
X93343D01*
X92130Y139549D01*
X91201Y138620D01*
X90698Y137407D01*
Y136093D01*
X91201Y134880D01*
X91734Y134346D01*
Y79035D01*
X90464Y78973D01*
X90202Y81630D01*
X88897Y85933D01*
X86777Y89899D01*
X83925Y93375D01*
X83877Y93327D01*
X83877Y93327D01*
X76285Y100919D01*
X76285Y100919D01*
X76323Y100957D01*
X73286Y103449D01*
X70371Y105007D01*
X69821Y105301D01*
X66061Y106442D01*
X62824Y106761D01*
X60787Y107849D01*
X58453Y109765D01*
X58447Y109758D01*
X53302Y114903D01*
Y115657D01*
X52799Y116870D01*
X51870Y117799D01*
X50657Y118302D01*
X49343D01*
X48130Y117799D01*
X47201Y116870D01*
X46698Y115657D01*
Y114343D01*
X47201Y113130D01*
X48130Y112201D01*
X49343Y111698D01*
X50097D01*
X55242Y106553D01*
X55205Y106516D01*
X58235Y104030D01*
X61011Y102546D01*
X61226Y102431D01*
Y102431D01*
X61275Y102420D01*
X61284Y102414D01*
X62146Y102234D01*
X62151Y102233D01*
X62151Y102233D01*
X65165Y101936D01*
X68063Y101057D01*
X70733Y99629D01*
X73074Y97708D01*
X73081Y97715D01*
X73081Y97715D01*
X80673Y90122D01*
X80687Y90113D01*
X82957Y87346D01*
X84653Y84175D01*
X85696Y80734D01*
X86047Y77172D01*
X86044Y77155D01*
Y34393D01*
X82296D01*
Y46626D01*
X82799Y47130D01*
X83302Y48343D01*
Y49657D01*
X82799Y50870D01*
X81870Y51799D01*
X80657Y52302D01*
X79343D01*
X78130Y51799D01*
X77201Y50870D01*
X76698Y49657D01*
Y48343D01*
X77201Y47130D01*
X77764Y46566D01*
Y34393D01*
X52326D01*
Y38121D01*
X55903Y41698D01*
X56657D01*
X57870Y42201D01*
X58799Y43130D01*
X59302Y44343D01*
Y45657D01*
X58799Y46870D01*
X57870Y47799D01*
X56657Y48302D01*
X55343D01*
X54130Y47799D01*
X53201Y46870D01*
X52698Y45657D01*
Y44903D01*
X48566Y40771D01*
X48111Y40826D01*
X47296Y41210D01*
Y46626D01*
X47799Y47130D01*
X48302Y48343D01*
Y49657D01*
X47799Y50870D01*
X46870Y51799D01*
X45657Y52302D01*
X44343D01*
X43130Y51799D01*
X42201Y50870D01*
X41698Y49657D01*
Y48343D01*
X42201Y47130D01*
X42764Y46566D01*
Y34393D01*
X37375D01*
Y55000D01*
X36972Y55972D01*
X36000Y56375D01*
X22598D01*
X21626Y55972D01*
X21223Y55000D01*
Y34393D01*
X10137D01*
X10088Y34425D01*
X10088Y34425D01*
X8286Y35172D01*
X7699Y35289D01*
X7125Y35463D01*
X6150Y35559D01*
X5948Y35539D01*
X5750Y35578D01*
X4078D01*
X4078Y415922D01*
X215922D01*
X215922Y54045D01*
D02*
G37*
G36*
X91906Y69133D02*
X92398Y68398D01*
X97794Y63001D01*
Y34393D01*
X90576D01*
Y69311D01*
X91846Y69437D01*
X91906Y69133D01*
D02*
G37*
G36*
X215000Y36000D02*
X205000D01*
Y31000D01*
X193657D01*
Y33698D01*
X194870Y34201D01*
X195799Y35130D01*
X196302Y36343D01*
Y37657D01*
X195799Y38870D01*
X194870Y39799D01*
X194740Y39853D01*
X194703Y40224D01*
X194790Y40420D01*
X195865Y41386D01*
X196530D01*
X197744Y41889D01*
X198672Y42818D01*
X199175Y44031D01*
Y45345D01*
X198672Y46558D01*
X198181Y47050D01*
X198076Y48170D01*
X198287Y48603D01*
X198986Y49302D01*
X199489Y50516D01*
Y51829D01*
X215000D01*
Y36000D01*
D02*
G37*
G36*
X36000Y31000D02*
Y28000D01*
X19000D01*
Y33000D01*
X22598D01*
Y55000D01*
X36000D01*
Y31000D01*
D02*
G37*
%LPC*%
G36*
X145657Y371302D02*
X144343D01*
X143130Y370799D01*
X142201Y369870D01*
X141698Y368657D01*
Y367343D01*
X142201Y366130D01*
X143130Y365201D01*
X144343Y364698D01*
X145657D01*
X146870Y365201D01*
X147799Y366130D01*
X148302Y367343D01*
Y368657D01*
X147799Y369870D01*
X146870Y370799D01*
X145657Y371302D01*
D02*
G37*
G36*
X135657D02*
X134343D01*
X133130Y370799D01*
X132201Y369870D01*
X131698Y368657D01*
Y367343D01*
X132201Y366130D01*
X133130Y365201D01*
X134343Y364698D01*
X135657D01*
X136870Y365201D01*
X137799Y366130D01*
X138302Y367343D01*
Y368657D01*
X137799Y369870D01*
X136870Y370799D01*
X135657Y371302D01*
D02*
G37*
G36*
X139479Y333308D02*
Y333266D01*
X136393D01*
Y333308D01*
X132059Y332967D01*
X127831Y331952D01*
X123814Y330288D01*
X120107Y328016D01*
X116801Y325192D01*
X116790Y325203D01*
X114194Y322040D01*
X112266Y318432D01*
X111078Y314517D01*
X110677Y310445D01*
X110734D01*
Y212521D01*
X110753Y212427D01*
X110317Y208002D01*
X108999Y203657D01*
X106859Y199653D01*
X104763Y197099D01*
X103958Y196163D01*
X103078Y195282D01*
X63837Y156042D01*
X63784Y155962D01*
X60347Y153141D01*
X56343Y151001D01*
X51998Y149683D01*
X47573Y149247D01*
X47479Y149266D01*
X41404D01*
X40870Y149799D01*
X39657Y150302D01*
X38343D01*
X37130Y149799D01*
X36201Y148870D01*
X35860Y148047D01*
X34590Y148300D01*
Y243927D01*
X84831Y294169D01*
X85393Y295009D01*
X85590Y296000D01*
Y314920D01*
X85799Y315130D01*
X86302Y316343D01*
Y317657D01*
X85799Y318870D01*
X84870Y319799D01*
X83657Y320302D01*
X82343D01*
X81130Y319799D01*
X80201Y318870D01*
X79698Y317657D01*
Y316343D01*
X80201Y315130D01*
X80410Y314920D01*
Y297073D01*
X30169Y246831D01*
X29607Y245991D01*
X29410Y245000D01*
Y89000D01*
X29607Y88009D01*
X30169Y87169D01*
X35169Y82169D01*
X35190Y82154D01*
X35201Y82130D01*
X36130Y81201D01*
X37343Y80698D01*
X38657D01*
X39870Y81201D01*
X40799Y82130D01*
X41220Y83145D01*
X41485Y83410D01*
X75920D01*
X76130Y83201D01*
X77343Y82698D01*
X78657D01*
X79870Y83201D01*
X80799Y84130D01*
X81302Y85343D01*
Y86657D01*
X80799Y87870D01*
X79870Y88799D01*
X78657Y89302D01*
X77343D01*
X76130Y88799D01*
X75920Y88590D01*
X40412D01*
X39421Y88393D01*
X38581Y87831D01*
X38052Y87302D01*
X37360D01*
X34590Y90073D01*
Y145700D01*
X35860Y145953D01*
X36201Y145130D01*
X37130Y144201D01*
X38343Y143698D01*
X39657D01*
X40870Y144201D01*
X41404Y144734D01*
X47479D01*
Y144692D01*
X51814Y145033D01*
X56041Y146048D01*
X60058Y147712D01*
X63765Y149984D01*
X67071Y152808D01*
X67042Y152837D01*
X106265Y192060D01*
X107192Y192929D01*
X107192Y192929D01*
X110016Y196235D01*
X112288Y199942D01*
X113952Y203959D01*
X114380Y205744D01*
X114405Y205781D01*
X114483Y206170D01*
X114967Y208187D01*
X115308Y212521D01*
X115266D01*
Y310445D01*
X115271D01*
X115584Y313620D01*
X116510Y316674D01*
X118014Y319488D01*
X120039Y321955D01*
X120973Y322764D01*
X123525Y324859D01*
X127529Y326999D01*
X131875Y328317D01*
X136299Y328753D01*
X136393Y328734D01*
X139479D01*
X139573Y328753D01*
X143998Y328317D01*
X148343Y326999D01*
X152347Y324859D01*
X155698Y322108D01*
Y321343D01*
X156201Y320130D01*
X157130Y319201D01*
X158343Y318698D01*
X159657D01*
X160870Y319201D01*
X161799Y320130D01*
X162302Y321343D01*
Y322657D01*
X161799Y323870D01*
X160870Y324799D01*
X159657Y325302D01*
X158943D01*
X155765Y328016D01*
X152058Y330288D01*
X148041Y331952D01*
X143813Y332967D01*
X139479Y333308D01*
D02*
G37*
G36*
X133187Y322302D02*
X131873D01*
X130659Y321799D01*
X130328Y321467D01*
X129498Y321001D01*
X128668Y321467D01*
X128336Y321799D01*
X127123Y322302D01*
X125809D01*
X124595Y321799D01*
X123666Y320871D01*
X123164Y319657D01*
Y318343D01*
X123666Y317130D01*
X124394Y316403D01*
X124510Y315815D01*
X124805Y315374D01*
X124877Y315200D01*
Y171866D01*
X124827D01*
X125221Y166857D01*
X126394Y161972D01*
X128317Y157331D01*
X130942Y153047D01*
X134204Y149227D01*
X134204Y149227D01*
X135138Y148364D01*
X140775Y142727D01*
X140866Y142667D01*
X143646Y139278D01*
X145763Y135318D01*
X147067Y131021D01*
X147496Y126659D01*
X147475Y126552D01*
Y76972D01*
X147400D01*
X147892Y73238D01*
X149333Y69758D01*
X151626Y66770D01*
X151626Y66770D01*
X152577Y65925D01*
X166355Y52147D01*
X167245Y51245D01*
X167245Y51245D01*
X168638Y50176D01*
X170259Y49504D01*
X172000Y49275D01*
Y49284D01*
X177596D01*
Y49246D01*
X180221Y49591D01*
X182668Y50605D01*
X184769Y52217D01*
Y52217D01*
X185543Y53166D01*
X186852Y54761D01*
X188387Y57634D01*
X189333Y60751D01*
X189422Y61657D01*
X189895Y62130D01*
X190397Y63343D01*
Y64657D01*
X189895Y65870D01*
X188966Y66799D01*
X187752Y67302D01*
X186439D01*
X185225Y66799D01*
X184893Y66467D01*
X184063Y66001D01*
X183234Y66467D01*
X182902Y66799D01*
X181688Y67302D01*
X180375D01*
X179161Y66799D01*
X178232Y65870D01*
X177729Y64657D01*
Y63343D01*
X178232Y62130D01*
X178507Y61855D01*
Y59939D01*
X178385Y59476D01*
X177586Y58537D01*
X177574Y58525D01*
X175500D01*
X175409Y58507D01*
X173219Y58943D01*
X171362Y60184D01*
X171311Y60260D01*
X158233Y73338D01*
X158187Y73369D01*
X157090Y75010D01*
X156705Y76946D01*
X156716Y77000D01*
Y126581D01*
X156766D01*
X156371Y131602D01*
X155196Y136499D01*
X153268Y141152D01*
X150637Y145447D01*
X147366Y149277D01*
X147330Y149241D01*
X147330Y149241D01*
X140785Y155785D01*
X140696Y155845D01*
X137929Y159218D01*
X135822Y163158D01*
X134525Y167434D01*
X134097Y171776D01*
X134118Y171881D01*
Y191400D01*
Y195035D01*
X134803D01*
X135769Y195227D01*
X136589Y195774D01*
X137136Y196594D01*
X137328Y197560D01*
Y202513D01*
X137136Y203479D01*
X136589Y204298D01*
Y205680D01*
X137136Y206500D01*
X137328Y207466D01*
Y212419D01*
X137136Y213385D01*
X136589Y214204D01*
X135769Y214752D01*
X134803Y214944D01*
X134118D01*
Y216236D01*
X134231Y216406D01*
X134424Y217372D01*
Y222325D01*
X134231Y223291D01*
X134118Y223460D01*
Y257000D01*
Y315200D01*
X134190Y315374D01*
X134485Y315815D01*
X134602Y316403D01*
X135329Y317130D01*
X135832Y318343D01*
Y319657D01*
X135329Y320871D01*
X134400Y321799D01*
X133187Y322302D01*
D02*
G37*
G36*
X181657Y378302D02*
X180343D01*
X179130Y377799D01*
X178201Y376870D01*
X177698Y375657D01*
Y375360D01*
X158927Y356590D01*
X130000D01*
X129009Y356393D01*
X128169Y355831D01*
X100169Y327831D01*
X99607Y326991D01*
X99410Y326000D01*
Y268073D01*
X48169Y216831D01*
X47607Y215991D01*
X47410Y215000D01*
Y163080D01*
X47201Y162870D01*
X46698Y161657D01*
Y160343D01*
X47201Y159130D01*
X48130Y158201D01*
X49343Y157698D01*
X50657D01*
X51870Y158201D01*
X52799Y159130D01*
X53302Y160343D01*
Y161657D01*
X52799Y162870D01*
X52590Y163080D01*
Y213927D01*
X103831Y265169D01*
X104393Y266009D01*
X104590Y267000D01*
Y324927D01*
X131073Y351410D01*
X160000D01*
X160991Y351607D01*
X161831Y352169D01*
X181360Y371698D01*
X181657D01*
X182870Y372201D01*
X183799Y373130D01*
X184302Y374343D01*
Y375657D01*
X183799Y376870D01*
X182870Y377799D01*
X181657Y378302D01*
D02*
G37*
G36*
X159657Y155302D02*
X158343D01*
X157130Y154799D01*
X156201Y153870D01*
X155698Y152657D01*
Y151343D01*
X156201Y150130D01*
X156795Y149535D01*
X157008Y148750D01*
X156795Y147965D01*
X156201Y147370D01*
X155698Y146157D01*
Y144843D01*
X156201Y143630D01*
X156563Y143267D01*
X156993Y142437D01*
X156563Y141608D01*
X156201Y141245D01*
X155698Y140031D01*
Y138718D01*
X156201Y137504D01*
X157130Y136575D01*
X158343Y136073D01*
X159657D01*
X160870Y136575D01*
X161799Y137504D01*
X162302Y138718D01*
Y140031D01*
X161799Y141245D01*
X161437Y141608D01*
X161007Y142437D01*
X161437Y143267D01*
X161799Y143630D01*
X162302Y144843D01*
Y146157D01*
X161799Y147370D01*
X161205Y147965D01*
X160993Y148750D01*
X161205Y149535D01*
X161799Y150130D01*
X162302Y151343D01*
Y152657D01*
X161799Y153870D01*
X160870Y154799D01*
X159657Y155302D01*
D02*
G37*
G36*
X117657Y124302D02*
X116343D01*
X115130Y123799D01*
X114201Y122870D01*
X113698Y121657D01*
Y120343D01*
X114201Y119130D01*
X115130Y118201D01*
X116343Y117698D01*
X117657D01*
X118870Y118201D01*
X119799Y119130D01*
X120302Y120343D01*
Y121657D01*
X119799Y122870D01*
X118870Y123799D01*
X117657Y124302D01*
D02*
G37*
G36*
X102657Y122302D02*
X101343D01*
X100130Y121799D01*
X99201Y120870D01*
X98698Y119657D01*
Y118343D01*
X99201Y117130D01*
X100130Y116201D01*
X101343Y115698D01*
X102657D01*
X103870Y116201D01*
X104799Y117130D01*
X105302Y118343D01*
Y119657D01*
X104799Y120870D01*
X103870Y121799D01*
X102657Y122302D01*
D02*
G37*
G36*
X112657Y80302D02*
X111343D01*
X110130Y79799D01*
X109201Y78870D01*
X108698Y77657D01*
Y76343D01*
X109201Y75130D01*
X110130Y74201D01*
X111343Y73698D01*
X112657D01*
X113870Y74201D01*
X114799Y75130D01*
X115302Y76343D01*
Y77657D01*
X114799Y78870D01*
X113870Y79799D01*
X112657Y80302D01*
D02*
G37*
%LPD*%
D17*
X195060Y15250D02*
Y31788D01*
X200060Y15250D02*
Y34198D01*
X199696D02*
X200060D01*
X38412Y84000D02*
X40412Y86000D01*
X78000D01*
X38000Y84000D02*
X38412D01*
X130000Y354000D02*
X160000D01*
X102000Y326000D02*
X130000Y354000D01*
X102000Y267000D02*
Y326000D01*
X50000Y215000D02*
X102000Y267000D01*
X160000Y354000D02*
X181000Y375000D01*
X50000Y161000D02*
Y215000D01*
X37000Y84000D02*
X38000D01*
X32000Y89000D02*
X37000Y84000D01*
X32000Y89000D02*
Y245000D01*
X83000Y296000D01*
Y317000D01*
X20060Y15250D02*
Y30000D01*
X25060Y15250D02*
Y32027D01*
X30060Y15250D02*
Y31802D01*
D61*
X56844Y108156D02*
G03*
X62151Y104508I12499J12499D01*
G01*
X69439Y102940D02*
G03*
X62151Y104508I-7287J-16155D01*
G01*
X74683Y99317D02*
G03*
X69439Y102940I-12532J-12532D01*
G01*
X40707Y115707D02*
G03*
X40000Y114000I1707J-1707D01*
G01*
X47479Y147000D02*
G03*
X65440Y154439I0J25400D01*
G01*
X88310Y77155D02*
G03*
X82275Y91725I-20604J0D01*
G01*
X99278Y150757D02*
G03*
X84534Y146040I0J-25400D01*
G01*
X78141Y140141D02*
G03*
X81208Y142713I-13141J18780D01*
G01*
X65000Y136000D02*
G03*
X78141Y140141I0J22921D01*
G01*
X58174Y133174D02*
G03*
X58172Y133172I6826J-6830D01*
G01*
X65000Y136000D02*
G03*
X58174Y133174I0J-9657D01*
G01*
X127561Y147439D02*
G03*
X119551Y150757I-8010J-8010D01*
G01*
X135000Y129479D02*
G03*
X127561Y147439I-25400J0D01*
G01*
X129950Y51950D02*
G03*
X135000Y64142I-12192J12192D01*
G01*
X118000Y47000D02*
G03*
X129950Y51950I0J16900D01*
G01*
X90060Y24324D02*
G03*
X88756Y27473I-4453J0D01*
G01*
X88310Y28697D02*
G03*
X88756Y27473I1905J0D01*
G01*
X112312Y206648D02*
G03*
X113000Y212521I-24712J5873D01*
G01*
X105561Y194561D02*
G03*
X112312Y206648I-17960J17960D01*
G01*
X118433Y323560D02*
G03*
X113000Y310445I13116J-13116D01*
G01*
X136393Y331000D02*
G03*
X118433Y323560I0J-25400D01*
G01*
X157439D02*
G03*
X139479Y331000I-17960J-17960D01*
G01*
X39000Y147000D02*
X47479D01*
X74683Y99317D02*
X82275Y91725D01*
X50000Y115000D02*
X56844Y108156D01*
X58172Y133172D02*
X58174Y133174D01*
X40707Y115707D02*
X58172Y133172D01*
X88310Y28697D02*
Y77155D01*
X84534Y146040D02*
X84534Y146040D01*
X81208Y142713D02*
X84534Y146040D01*
X65440Y154439D02*
X105561Y194561D01*
X99278Y150757D02*
X119551D01*
X135000Y64142D02*
Y129479D01*
X90060Y15250D02*
Y24324D01*
X113000Y212521D02*
Y310445D01*
X100060Y15250D02*
Y63940D01*
X94000Y70000D02*
X100060Y63940D01*
X94000Y70000D02*
Y136750D01*
X125000Y63000D02*
Y136750D01*
X105060Y43060D02*
X125000Y63000D01*
X136393Y331000D02*
X139479D01*
X157439Y323560D02*
X159000Y322000D01*
X105060Y15250D02*
Y43060D01*
X80030Y15280D02*
Y48970D01*
X45030Y15280D02*
Y48970D01*
X50060Y39060D02*
X56000Y45000D01*
X50060Y15250D02*
Y39060D01*
D62*
X182978Y54051D02*
G03*
X187096Y63992I-9941J9941D01*
G01*
X177596Y51809D02*
G03*
X182956Y54029I0J7581D01*
G01*
X169037Y53036D02*
G03*
X172000Y51809I2964J2963D01*
G01*
X150000Y76972D02*
G03*
X153464Y68609I11828J0D01*
G01*
X150000Y126552D02*
G03*
X142561Y144513I-25400J0D01*
G01*
X127402Y171866D02*
G03*
X136025Y151048I29441J0D01*
G01*
X127402Y315696D02*
G03*
X127092Y316445I-1059J0D01*
G01*
X126782Y317194D02*
G03*
X127092Y316445I1059J0D01*
G01*
X126782Y318237D02*
G03*
X126466Y319000I-1079J0D01*
G01*
X177586Y56000D02*
G03*
X180000Y57000I0J3414D01*
G01*
X169525Y58475D02*
G03*
X175500Y56000I5975J5975D01*
G01*
X154191Y77000D02*
G03*
X156447Y71553I7704J0D01*
G01*
X154191Y126581D02*
G03*
X145545Y147455I-29521J0D01*
G01*
X131593Y171881D02*
G03*
X139000Y154000I25288J0D01*
G01*
X131904Y316445D02*
G03*
X131593Y315696I749J-749D01*
G01*
X132530Y319000D02*
G03*
X132214Y318237I763J-763D01*
G01*
X180000Y57000D02*
G03*
X181031Y59490I-2490J2490D01*
G01*
X131904Y316445D02*
G03*
X132214Y317194I-749J749D01*
G01*
X131593Y222325D02*
Y257000D01*
Y222325D02*
X131898D01*
Y217372D02*
Y222325D01*
X131593Y217372D02*
X131898D01*
X131593Y212419D02*
Y217372D01*
Y212419D02*
X134803D01*
Y207466D02*
Y212419D01*
X131593Y207466D02*
X134803D01*
X131593Y202513D02*
Y207466D01*
Y202513D02*
X134803D01*
Y197560D02*
Y202513D01*
X131593Y197560D02*
X134803D01*
X131593Y191400D02*
Y197560D01*
Y257000D02*
Y315696D01*
Y171881D02*
Y191400D01*
X182956Y54029D02*
X182978Y54051D01*
X172000Y51809D02*
X177596D01*
X150000Y76972D02*
Y126552D01*
X136025Y151048D02*
X142561Y144513D01*
X127402Y171866D02*
Y315696D01*
X126782Y317194D02*
Y318237D01*
X175500Y56000D02*
X177586D01*
X154191Y77000D02*
Y126581D01*
X139000Y154000D02*
X145545Y147455D01*
X132214Y317194D02*
Y318237D01*
X181031Y59490D02*
Y64000D01*
X187096Y63992D02*
Y64000D01*
X156447Y71553D02*
X169525Y58475D01*
X153464Y68609D02*
X169037Y53036D01*
D65*
X69468Y121045D02*
D03*
X40000Y114000D02*
D03*
X50000Y115000D02*
D03*
X39000Y147000D02*
D03*
X118000Y47000D02*
D03*
X200000Y78350D02*
D03*
X207794Y79007D02*
D03*
X203112Y61996D02*
D03*
X211343Y71000D02*
D03*
X212000Y61000D02*
D03*
X63000Y38000D02*
D03*
X193000Y37000D02*
D03*
X208000Y193000D02*
D03*
X205000Y239000D02*
D03*
X206000Y215000D02*
D03*
Y259000D02*
D03*
Y268000D02*
D03*
Y276000D02*
D03*
X213640Y410220D02*
D03*
X209830Y402600D02*
D03*
X213640Y394980D02*
D03*
X209830Y387360D02*
D03*
X206020Y410220D02*
D03*
X202210Y402600D02*
D03*
X206020Y394980D02*
D03*
X202210Y387360D02*
D03*
Y174000D02*
D03*
Y158760D02*
D03*
Y143520D02*
D03*
X198400Y410220D02*
D03*
X194590Y402600D02*
D03*
X198400Y394980D02*
D03*
X194590Y387360D02*
D03*
X190780Y410220D02*
D03*
X186970Y402600D02*
D03*
X190780Y394980D02*
D03*
X186970Y387360D02*
D03*
X183160Y410220D02*
D03*
X179350Y402600D02*
D03*
X183160Y394980D02*
D03*
X179350Y387360D02*
D03*
X175540Y410220D02*
D03*
X171730Y402600D02*
D03*
X175540Y394980D02*
D03*
X171730Y387360D02*
D03*
X167920Y410220D02*
D03*
X164110Y402600D02*
D03*
X167920Y394980D02*
D03*
X164110Y387360D02*
D03*
X160300Y410220D02*
D03*
X156490Y402600D02*
D03*
X160300Y394980D02*
D03*
X156490Y387360D02*
D03*
X152680Y410220D02*
D03*
X148870Y402600D02*
D03*
X152680Y394980D02*
D03*
X148870Y387360D02*
D03*
X145060Y410220D02*
D03*
X141250Y402600D02*
D03*
X145060Y394980D02*
D03*
X141250Y387360D02*
D03*
X137440Y394980D02*
D03*
X133630Y387360D02*
D03*
X126010D02*
D03*
X110770Y372120D02*
D03*
X106960Y379740D02*
D03*
X103150Y372120D02*
D03*
X106960Y364500D02*
D03*
X103150Y341640D02*
D03*
X95530Y387360D02*
D03*
X99340Y379740D02*
D03*
X95530Y372120D02*
D03*
X99340Y364500D02*
D03*
X95530Y341640D02*
D03*
Y311160D02*
D03*
Y295920D02*
D03*
Y280680D02*
D03*
X87910Y387360D02*
D03*
X91720Y379740D02*
D03*
X87910Y372120D02*
D03*
X91720Y364500D02*
D03*
X87910Y341640D02*
D03*
Y326400D02*
D03*
X91720Y303540D02*
D03*
Y288300D02*
D03*
X87910Y280680D02*
D03*
X91720Y273060D02*
D03*
X87910Y265440D02*
D03*
X80290Y402600D02*
D03*
X84100Y394980D02*
D03*
X80290Y387360D02*
D03*
X84100Y379740D02*
D03*
X80290Y372120D02*
D03*
X84100Y364500D02*
D03*
Y334020D02*
D03*
X80290Y326400D02*
D03*
Y280680D02*
D03*
X84100Y273060D02*
D03*
X80290Y265440D02*
D03*
X76480Y410220D02*
D03*
X72670Y402600D02*
D03*
X76480Y394980D02*
D03*
X72670Y387360D02*
D03*
X76480Y379740D02*
D03*
X72670Y372120D02*
D03*
X76480Y334020D02*
D03*
X72670Y326400D02*
D03*
X76480Y318780D02*
D03*
Y273060D02*
D03*
X72670Y265440D02*
D03*
X68860Y410220D02*
D03*
X65050Y402600D02*
D03*
X68860Y394980D02*
D03*
X65050Y387360D02*
D03*
X68860Y379740D02*
D03*
X65050Y372120D02*
D03*
X68860Y334020D02*
D03*
X65050Y326400D02*
D03*
X68860Y318780D02*
D03*
Y273060D02*
D03*
X65050Y265440D02*
D03*
X61240Y379740D02*
D03*
X57430Y372120D02*
D03*
X61240Y334020D02*
D03*
X57430Y326400D02*
D03*
Y280680D02*
D03*
X53620Y379740D02*
D03*
X49810Y372120D02*
D03*
Y280680D02*
D03*
X42190D02*
D03*
X46000Y273060D02*
D03*
X42190Y265440D02*
D03*
X38380Y410220D02*
D03*
X34570Y402600D02*
D03*
Y280680D02*
D03*
X38380Y273060D02*
D03*
X34570Y265440D02*
D03*
X30760Y410220D02*
D03*
X26950Y326400D02*
D03*
X30760Y318780D02*
D03*
X26950Y311160D02*
D03*
X30760Y303540D02*
D03*
X26950Y295920D02*
D03*
X30760Y288300D02*
D03*
X26950Y280680D02*
D03*
X30760Y273060D02*
D03*
X26950Y265440D02*
D03*
X19330Y372120D02*
D03*
X23140Y364500D02*
D03*
X19330Y356880D02*
D03*
X23140Y349260D02*
D03*
X19330Y341640D02*
D03*
X23140Y334020D02*
D03*
X19330Y326400D02*
D03*
X23140Y318780D02*
D03*
X19330Y311160D02*
D03*
X23140Y303540D02*
D03*
X19330Y295920D02*
D03*
X23140Y288300D02*
D03*
X19330Y280680D02*
D03*
X23140Y273060D02*
D03*
X19330Y265440D02*
D03*
Y250200D02*
D03*
Y234960D02*
D03*
Y219720D02*
D03*
Y204480D02*
D03*
Y189240D02*
D03*
Y174000D02*
D03*
Y158760D02*
D03*
Y143520D02*
D03*
Y128280D02*
D03*
Y113040D02*
D03*
Y97800D02*
D03*
Y82560D02*
D03*
Y67320D02*
D03*
X15520Y379740D02*
D03*
X11710Y372120D02*
D03*
X15520Y364500D02*
D03*
X11710Y356880D02*
D03*
X15520Y349260D02*
D03*
X11710Y341640D02*
D03*
X15520Y334020D02*
D03*
X11710Y326400D02*
D03*
X15520Y318780D02*
D03*
X11710Y311160D02*
D03*
X15520Y303540D02*
D03*
X11710Y295920D02*
D03*
X15520Y288300D02*
D03*
X11710Y280680D02*
D03*
X15520Y273060D02*
D03*
X11710Y265440D02*
D03*
X15520Y257820D02*
D03*
X11710Y250200D02*
D03*
X15520Y242580D02*
D03*
X11710Y234960D02*
D03*
X15520Y227340D02*
D03*
X11710Y219720D02*
D03*
X15520Y212100D02*
D03*
X11710Y204480D02*
D03*
X15520Y196860D02*
D03*
X11710Y189240D02*
D03*
X15520Y181620D02*
D03*
X11710Y174000D02*
D03*
X15520Y166380D02*
D03*
X11710Y158760D02*
D03*
X15520Y151140D02*
D03*
X11710Y143520D02*
D03*
X15520Y135900D02*
D03*
X11710Y128280D02*
D03*
X15520Y120660D02*
D03*
X11710Y113040D02*
D03*
X15520Y105420D02*
D03*
X11710Y97800D02*
D03*
X15520Y90180D02*
D03*
X11710Y82560D02*
D03*
X15520Y74940D02*
D03*
X11710Y67320D02*
D03*
X15520Y59700D02*
D03*
X32151Y339810D02*
D03*
X31576Y332800D02*
D03*
X35076Y326800D02*
D03*
X38651Y320417D02*
D03*
X43408Y314602D02*
D03*
X55998Y314097D02*
D03*
X54580Y320095D02*
D03*
X50238Y325800D02*
D03*
X47228Y332057D02*
D03*
X46887Y338234D02*
D03*
X46651Y344528D02*
D03*
X41962Y367714D02*
D03*
X39820Y373823D02*
D03*
X31485Y353188D02*
D03*
X30909Y359800D02*
D03*
X29145Y365800D02*
D03*
X33000Y393477D02*
D03*
X23000Y383750D02*
D03*
X24523Y377500D02*
D03*
X28054Y371915D02*
D03*
X31719Y347000D02*
D03*
X46267Y350969D02*
D03*
X43782Y379467D02*
D03*
X41000Y393477D02*
D03*
X9000Y395000D02*
D03*
Y408000D02*
D03*
X62000Y394000D02*
D03*
X73000Y38000D02*
D03*
X187096Y64000D02*
D03*
X181031D02*
D03*
X78000Y86000D02*
D03*
X132530Y319000D02*
D03*
X126466D02*
D03*
X112000Y77000D02*
D03*
X106000Y106000D02*
D03*
X117000Y121000D02*
D03*
X102000Y119000D02*
D03*
X125000Y136750D02*
D03*
X94000D02*
D03*
X38000Y84000D02*
D03*
X83000Y317000D02*
D03*
X159000Y322000D02*
D03*
X50000Y161000D02*
D03*
X190000Y354000D02*
D03*
X177000Y340000D02*
D03*
X181000Y375000D02*
D03*
X145000Y368000D02*
D03*
X135000D02*
D03*
X95000Y334000D02*
D03*
X79000Y360000D02*
D03*
X39010Y160198D02*
D03*
X64425Y314602D02*
D03*
X36000Y314802D02*
D03*
X199000Y90000D02*
D03*
Y101000D02*
D03*
X198000Y117000D02*
D03*
Y126000D02*
D03*
X188000Y136000D02*
D03*
Y148000D02*
D03*
Y160000D02*
D03*
X159000Y152000D02*
D03*
Y145500D02*
D03*
Y139375D02*
D03*
X176000Y44000D02*
D03*
X195873Y44688D02*
D03*
X196187Y51172D02*
D03*
X111000Y35000D02*
D03*
X204114Y40000D02*
D03*
X203458Y48255D02*
D03*
X211000Y40000D02*
D03*
Y47870D02*
D03*
X152000Y36000D02*
D03*
X137000D02*
D03*
X123000Y35000D02*
D03*
X93000Y34000D02*
D03*
X33000Y31000D02*
D03*
Y38000D02*
D03*
X32880Y45166D02*
D03*
X33000Y51645D02*
D03*
X15000Y50312D02*
D03*
X12791Y42000D02*
D03*
X6395Y41971D02*
D03*
X6826Y50312D02*
D03*
X80000Y49000D02*
D03*
X45000D02*
D03*
X56000Y45000D02*
D03*
D67*
X140060Y15250D02*
D03*
X135060D02*
D03*
X130060D02*
D03*
X125060D02*
D03*
X120060D02*
D03*
X115060D02*
D03*
X110060D02*
D03*
X155060D02*
D03*
X150060D02*
D03*
X80060D02*
D03*
X90060D02*
D03*
X85060D02*
D03*
X95060D02*
D03*
X75060D02*
D03*
X70060D02*
D03*
X65060D02*
D03*
X60060D02*
D03*
X55060D02*
D03*
X50060D02*
D03*
X45060D02*
D03*
X40060D02*
D03*
X35060D02*
D03*
X30060D02*
D03*
X25060D02*
D03*
X100060D02*
D03*
X105060D02*
D03*
X145060D02*
D03*
X185060D02*
D03*
X200060D02*
D03*
X195060D02*
D03*
X190060D02*
D03*
X180060D02*
D03*
X20060D02*
D03*
D68*
X80030Y15280D02*
X80060Y15250D01*
X80000Y49000D02*
X80030Y48970D01*
X45030Y15280D02*
X45060Y15250D01*
X45000Y49000D02*
X45030Y48970D01*
D69*
X110000Y420000D02*
D03*
M02*
